(kicad_pcb
	(version 20260206)
	(generator "pcbnew")
	(generator_version "10.0")
	(general
		(thickness 1.6)
		(legacy_teardrops no)
	)
	(paper "A4")
	(title_block
		(title "01162023_DA0F0TEBIF0_F0T_Expander_BD_F_brd_V02_OCP.brd")
		(comment 1 "Grand Teton / footprints 1106-1111 of 9728")
	)
	(layers
		(0 "F.Cu" signal "TOP")
		(4 "In1.Cu" signal "GND")
		(6 "In2.Cu" signal "VCC")
		(8 "In3.Cu" signal "VCC1")
		(10 "In4.Cu" signal "GND1")
		(12 "In5.Cu" signal "IN1")
		(14 "In6.Cu" signal "GND2")
		(16 "In7.Cu" signal "IN2")
		(18 "In8.Cu" signal "GND3")
		(20 "In9.Cu" signal "IN3")
		(22 "In10.Cu" signal "GND4")
		(24 "In11.Cu" signal "IN4")
		(26 "In12.Cu" signal "GND5")
		(28 "In13.Cu" signal "IN5")
		(30 "In14.Cu" signal "GND6")
		(32 "In15.Cu" signal "IN6")
		(34 "In16.Cu" signal "GND7")
		(2 "B.Cu" signal "BOTTOM")
		(9 "F.Adhes" user "F.Adhesive")
		(11 "B.Adhes" user "B.Adhesive")
		(13 "F.Paste" user "Package Geometry/Pastemask Top")
		(15 "B.Paste" user "Package Geometry/Pastemask Bottom")
		(5 "F.SilkS" user "Ref Des/Silkscreen Top")
		(7 "B.SilkS" user "Ref Des/Silkscreen Bottom")
		(1 "F.Mask" user "Board Geometry/Soldermask Top")
		(3 "B.Mask" user "Board Geometry/Soldermask Bottom")
		(17 "Dwgs.User" user "User.Drawings")
		(19 "Cmts.User" user "User.Comments")
		(21 "Eco1.User" user "User.Eco1")
		(23 "Eco2.User" user "User.Eco2")
		(25 "Edge.Cuts" user "Board Geometry/Outline")
		(27 "Margin" user)
		(31 "F.CrtYd" user "Package Geometry/Place Bound Top")
		(29 "B.CrtYd" user "Package Geometry/Place Bound Bottom")
		(35 "F.Fab" user "Ref Des/Assembly Top")
		(33 "B.Fab" user "Ref Des/Assembly Bottom")
	)
	(footprint ""
		(layer "F.Cu")
		(at 236.004608 -77.53477 180)
		(property "Reference" "R1004"
			(at 0 0 180)
			(layer "F.SilkS")
			(hide yes)
			(effects
				(font
					(size 1.27 1.27)
				)
			)
		)
		(property "Value" ""
			(at 0 0 180)
			(layer "F.Fab")
			(effects
				(font
					(size 1.27 1.27)
				)
			)
		)
		(duplicate_pad_numbers_are_jumpers no)
		(fp_line
			(start 0.7874 0.4064)
			(end -0.7874 0.4064)
			(stroke
				(width 0.1524)
				(type default)
			)
			(layer "F.SilkS")
		)
		(fp_line
			(start 0.7874 -0.4064)
			(end 0.7874 0.4064)
			(stroke
				(width 0.1524)
				(type default)
			)
			(layer "F.SilkS")
		)
		(fp_line
			(start -0.7874 0.4064)
			(end -0.7874 -0.4064)
			(stroke
				(width 0.1524)
				(type default)
			)
			(layer "F.SilkS")
		)
		(fp_line
			(start -0.7874 -0.4064)
			(end 0.7874 -0.4064)
			(stroke
				(width 0.1524)
				(type default)
			)
			(layer "F.SilkS")
		)
		(fp_line
			(start 0.67945 0.3048)
			(end 0.120396 0.3048)
			(stroke
				(width 0.1)
				(type default)
			)
			(layer "F.Fab")
		)
		(fp_line
			(start 0.67945 -0.3048)
			(end 0.67945 0.3048)
			(stroke
				(width 0.1)
				(type default)
			)
			(layer "F.Fab")
		)
		(fp_line
			(start 0.12065 -0.2794)
			(end 0.12065 -0.3048)
			(stroke
				(width 0.1)
				(type default)
			)
			(layer "F.Fab")
		)
		(fp_line
			(start 0.12065 -0.3048)
			(end 0.67945 -0.3048)
			(stroke
				(width 0.1)
				(type default)
			)
			(layer "F.Fab")
		)
		(fp_line
			(start 0.120396 0.3048)
			(end 0.120396 0.2794)
			(stroke
				(width 0.1)
				(type default)
			)
			(layer "F.Fab")
		)
		(fp_line
			(start 0.120396 0.2794)
			(end -0.12065 0.2794)
			(stroke
				(width 0.1)
				(type default)
			)
			(layer "F.Fab")
		)
		(fp_line
			(start -0.12065 0.3048)
			(end -0.67945 0.3048)
			(stroke
				(width 0.1)
				(type default)
			)
			(layer "F.Fab")
		)
		(fp_line
			(start -0.12065 0.2794)
			(end -0.12065 0.3048)
			(stroke
				(width 0.1)
				(type default)
			)
			(layer "F.Fab")
		)
		(fp_line
			(start -0.12065 -0.2794)
			(end 0.12065 -0.2794)
			(stroke
				(width 0.1)
				(type default)
			)
			(layer "F.Fab")
		)
		(fp_line
			(start -0.12065 -0.305054)
			(end -0.12065 -0.2794)
			(stroke
				(width 0.1)
				(type default)
			)
			(layer "F.Fab")
		)
		(fp_line
			(start -0.67945 0.3048)
			(end -0.67945 -0.305054)
			(stroke
				(width 0.1)
				(type default)
			)
			(layer "F.Fab")
		)
		(fp_line
			(start -0.67945 -0.305054)
			(end -0.12065 -0.305054)
			(stroke
				(width 0.1)
				(type default)
			)
			(layer "F.Fab")
		)
		(pad "1" smd circle
			(at -0.40005 0 180)
			(size 0 0)
			(layers "F.Cu" "F.Mask" "F.Paste")
			(net "P3V3_AUX")
		)
		(pad "2" smd circle
			(at 0.40005 0 180)
			(size 0 0)
			(layers "F.Cu" "F.Mask" "F.Paste")
			(net "PWRGD_P3V3_AUX_MUX_N")
		)
	)
	(footprint ""
		(layer "F.Cu")
		(at 238.124746 -119.111268)
		(property "Reference" "PR6902"
			(at 0 0 0)
			(layer "F.SilkS")
			(hide yes)
			(effects
				(font
					(size 1.27 1.27)
				)
			)
		)
		(property "Value" ""
			(at 0 0 0)
			(layer "F.Fab")
			(effects
				(font
					(size 1.27 1.27)
				)
			)
		)
		(duplicate_pad_numbers_are_jumpers no)
		(fp_line
			(start -0.7874 -0.4064)
			(end 0.7874 -0.4064)
			(stroke
				(width 0.1524)
				(type default)
			)
			(layer "F.SilkS")
		)
		(fp_line
			(start -0.7874 0.4064)
			(end -0.7874 -0.4064)
			(stroke
				(width 0.1524)
				(type default)
			)
			(layer "F.SilkS")
		)
		(fp_line
			(start 0.7874 -0.4064)
			(end 0.7874 0.4064)
			(stroke
				(width 0.1524)
				(type default)
			)
			(layer "F.SilkS")
		)
		(fp_line
			(start 0.7874 0.4064)
			(end -0.7874 0.4064)
			(stroke
				(width 0.1524)
				(type default)
			)
			(layer "F.SilkS")
		)
		(fp_line
			(start -0.67945 -0.305054)
			(end -0.12065 -0.305054)
			(stroke
				(width 0.1)
				(type default)
			)
			(layer "F.Fab")
		)
		(fp_line
			(start -0.67945 0.3048)
			(end -0.67945 -0.305054)
			(stroke
				(width 0.1)
				(type default)
			)
			(layer "F.Fab")
		)
		(fp_line
			(start -0.12065 -0.305054)
			(end -0.12065 -0.2794)
			(stroke
				(width 0.1)
				(type default)
			)
			(layer "F.Fab")
		)
		(fp_line
			(start -0.12065 -0.2794)
			(end 0.12065 -0.2794)
			(stroke
				(width 0.1)
				(type default)
			)
			(layer "F.Fab")
		)
		(fp_line
			(start -0.12065 0.2794)
			(end -0.12065 0.3048)
			(stroke
				(width 0.1)
				(type default)
			)
			(layer "F.Fab")
		)
		(fp_line
			(start -0.12065 0.3048)
			(end -0.67945 0.3048)
			(stroke
				(width 0.1)
				(type default)
			)
			(layer "F.Fab")
		)
		(fp_line
			(start 0.120396 0.2794)
			(end -0.12065 0.2794)
			(stroke
				(width 0.1)
				(type default)
			)
			(layer "F.Fab")
		)
		(fp_line
			(start 0.120396 0.3048)
			(end 0.120396 0.2794)
			(stroke
				(width 0.1)
				(type default)
			)
			(layer "F.Fab")
		)
		(fp_line
			(start 0.12065 -0.3048)
			(end 0.67945 -0.3048)
			(stroke
				(width 0.1)
				(type default)
			)
			(layer "F.Fab")
		)
		(fp_line
			(start 0.12065 -0.2794)
			(end 0.12065 -0.3048)
			(stroke
				(width 0.1)
				(type default)
			)
			(layer "F.Fab")
		)
		(fp_line
			(start 0.67945 -0.3048)
			(end 0.67945 0.3048)
			(stroke
				(width 0.1)
				(type default)
			)
			(layer "F.Fab")
		)
		(fp_line
			(start 0.67945 0.3048)
			(end 0.120396 0.3048)
			(stroke
				(width 0.1)
				(type default)
			)
			(layer "F.Fab")
		)
		(pad "1" smd circle
			(at -0.40005 0)
			(size 0 0)
			(layers "F.Cu" "F.Mask" "F.Paste")
			(net "P12V_NIC3_CO_IMON_VR")
		)
		(pad "2" smd circle
			(at 0.40005 0)
			(size 0 0)
			(layers "F.Cu" "F.Mask" "F.Paste")
			(net "GND")
		)
	)
	(footprint ""
		(layer "F.Cu")
		(at 88.288114 -100.459032 90)
		(property "Reference" "R700"
			(at 0 0 90)
			(layer "F.SilkS")
			(hide yes)
			(effects
				(font
					(size 1.27 1.27)
				)
			)
		)
		(property "Value" ""
			(at 0 0 90)
			(layer "F.Fab")
			(effects
				(font
					(size 1.27 1.27)
				)
			)
		)
		(duplicate_pad_numbers_are_jumpers no)
		(fp_line
			(start 0.7874 -0.4064)
			(end 0.7874 0.4064)
			(stroke
				(width 0.1524)
				(type default)
			)
			(layer "F.SilkS")
		)
		(fp_line
			(start -0.7874 -0.4064)
			(end 0.7874 -0.4064)
			(stroke
				(width 0.1524)
				(type default)
			)
			(layer "F.SilkS")
		)
		(fp_line
			(start 0.7874 0.4064)
			(end -0.7874 0.4064)
			(stroke
				(width 0.1524)
				(type default)
			)
			(layer "F.SilkS")
		)
		(fp_line
			(start -0.7874 0.4064)
			(end -0.7874 -0.4064)
			(stroke
				(width 0.1524)
				(type default)
			)
			(layer "F.SilkS")
		)
		(fp_line
			(start -0.12065 -0.305054)
			(end -0.12065 -0.2794)
			(stroke
				(width 0.1)
				(type default)
			)
			(layer "F.Fab")
		)
		(fp_line
			(start -0.67945 -0.305054)
			(end -0.12065 -0.305054)
			(stroke
				(width 0.1)
				(type default)
			)
			(layer "F.Fab")
		)
		(fp_line
			(start 0.67945 -0.3048)
			(end 0.67945 0.3048)
			(stroke
				(width 0.1)
				(type default)
			)
			(layer "F.Fab")
		)
		(fp_line
			(start 0.12065 -0.3048)
			(end 0.67945 -0.3048)
			(stroke
				(width 0.1)
				(type default)
			)
			(layer "F.Fab")
		)
		(fp_line
			(start 0.12065 -0.2794)
			(end 0.12065 -0.3048)
			(stroke
				(width 0.1)
				(type default)
			)
			(layer "F.Fab")
		)
		(fp_line
			(start -0.12065 -0.2794)
			(end 0.12065 -0.2794)
			(stroke
				(width 0.1)
				(type default)
			)
			(layer "F.Fab")
		)
		(fp_line
			(start 0.120396 0.2794)
			(end -0.12065 0.2794)
			(stroke
				(width 0.1)
				(type default)
			)
			(layer "F.Fab")
		)
		(fp_line
			(start -0.12065 0.2794)
			(end -0.12065 0.3048)
			(stroke
				(width 0.1)
				(type default)
			)
			(layer "F.Fab")
		)
		(fp_line
			(start 0.67945 0.3048)
			(end 0.120396 0.3048)
			(stroke
				(width 0.1)
				(type default)
			)
			(layer "F.Fab")
		)
		(fp_line
			(start 0.120396 0.3048)
			(end 0.120396 0.2794)
			(stroke
				(width 0.1)
				(type default)
			)
			(layer "F.Fab")
		)
		(fp_line
			(start -0.12065 0.3048)
			(end -0.67945 0.3048)
			(stroke
				(width 0.1)
				(type default)
			)
			(layer "F.Fab")
		)
		(fp_line
			(start -0.67945 0.3048)
			(end -0.67945 -0.305054)
			(stroke
				(width 0.1)
				(type default)
			)
			(layer "F.Fab")
		)
		(pad "1" smd circle
			(at -0.40005 0 90)
			(size 0 0)
			(layers "F.Cu" "F.Mask" "F.Paste")
			(net "P12V_NIC1_R")
		)
		(pad "2" smd circle
			(at 0.40005 0 90)
			(size 0 0)
			(layers "F.Cu" "F.Mask" "F.Paste")
			(net "P12V_NIC1_VIN_P")
		)
	)
	(footprint ""
		(layer "F.Cu")
		(at 144.389856 -192.144396 -90)
		(property "Reference" "R6673"
			(at 0 0 270)
			(layer "F.SilkS")
			(hide yes)
			(effects
				(font
					(size 1.27 1.27)
				)
			)
		)
		(property "Value" ""
			(at 0 0 270)
			(layer "F.Fab")
			(effects
				(font
					(size 1.27 1.27)
				)
			)
		)
		(duplicate_pad_numbers_are_jumpers no)
		(fp_line
			(start -0.7874 0.4064)
			(end -0.7874 -0.4064)
			(stroke
				(width 0.1524)
				(type default)
			)
			(layer "F.SilkS")
		)
		(fp_line
			(start 0.7874 0.4064)
			(end -0.7874 0.4064)
			(stroke
				(width 0.1524)
				(type default)
			)
			(layer "F.SilkS")
		)
		(fp_line
			(start -0.7874 -0.4064)
			(end 0.7874 -0.4064)
			(stroke
				(width 0.1524)
				(type default)
			)
			(layer "F.SilkS")
		)
		(fp_line
			(start 0.7874 -0.4064)
			(end 0.7874 0.4064)
			(stroke
				(width 0.1524)
				(type default)
			)
			(layer "F.SilkS")
		)
		(fp_line
			(start -0.67945 0.3048)
			(end -0.67945 -0.305054)
			(stroke
				(width 0.1)
				(type default)
			)
			(layer "F.Fab")
		)
		(fp_line
			(start -0.12065 0.3048)
			(end -0.67945 0.3048)
			(stroke
				(width 0.1)
				(type default)
			)
			(layer "F.Fab")
		)
		(fp_line
			(start 0.120396 0.3048)
			(end 0.120396 0.2794)
			(stroke
				(width 0.1)
				(type default)
			)
			(layer "F.Fab")
		)
		(fp_line
			(start 0.67945 0.3048)
			(end 0.120396 0.3048)
			(stroke
				(width 0.1)
				(type default)
			)
			(layer "F.Fab")
		)
		(fp_line
			(start -0.12065 0.2794)
			(end -0.12065 0.3048)
			(stroke
				(width 0.1)
				(type default)
			)
			(layer "F.Fab")
		)
		(fp_line
			(start 0.120396 0.2794)
			(end -0.12065 0.2794)
			(stroke
				(width 0.1)
				(type default)
			)
			(layer "F.Fab")
		)
		(fp_line
			(start -0.12065 -0.2794)
			(end 0.12065 -0.2794)
			(stroke
				(width 0.1)
				(type default)
			)
			(layer "F.Fab")
		)
		(fp_line
			(start 0.12065 -0.2794)
			(end 0.12065 -0.3048)
			(stroke
				(width 0.1)
				(type default)
			)
			(layer "F.Fab")
		)
		(fp_line
			(start 0.12065 -0.3048)
			(end 0.67945 -0.3048)
			(stroke
				(width 0.1)
				(type default)
			)
			(layer "F.Fab")
		)
		(fp_line
			(start 0.67945 -0.3048)
			(end 0.67945 0.3048)
			(stroke
				(width 0.1)
				(type default)
			)
			(layer "F.Fab")
		)
		(fp_line
			(start -0.67945 -0.305054)
			(end -0.12065 -0.305054)
			(stroke
				(width 0.1)
				(type default)
			)
			(layer "F.Fab")
		)
		(fp_line
			(start -0.12065 -0.305054)
			(end -0.12065 -0.2794)
			(stroke
				(width 0.1)
				(type default)
			)
			(layer "F.Fab")
		)
		(pad "1" smd circle
			(at -0.40005 0 270)
			(size 0 0)
			(layers "F.Cu" "F.Mask" "F.Paste")
			(net "NIC4_CLK_EN_BUF_R_N")
		)
		(pad "2" smd circle
			(at 0.40005 0 270)
			(size 0 0)
			(layers "F.Cu" "F.Mask" "F.Paste")
			(net "P3V3")
		)
	)
	(footprint ""
		(layer "F.Cu")
		(at 284.659324 -22.955504 90)
		(property "Reference" "R1700"
			(at 0 0 90)
			(layer "F.SilkS")
			(hide yes)
			(effects
				(font
					(size 1.27 1.27)
				)
			)
		)
		(property "Value" ""
			(at 0 0 90)
			(layer "F.Fab")
			(effects
				(font
					(size 1.27 1.27)
				)
			)
		)
		(duplicate_pad_numbers_are_jumpers no)
		(fp_line
			(start 0.7874 -0.4064)
			(end 0.7874 0.4064)
			(stroke
				(width 0.1524)
				(type default)
			)
			(layer "F.SilkS")
		)
		(fp_line
			(start -0.7874 -0.4064)
			(end 0.7874 -0.4064)
			(stroke
				(width 0.1524)
				(type default)
			)
			(layer "F.SilkS")
		)
		(fp_line
			(start 0.7874 0.4064)
			(end -0.7874 0.4064)
			(stroke
				(width 0.1524)
				(type default)
			)
			(layer "F.SilkS")
		)
		(fp_line
			(start -0.7874 0.4064)
			(end -0.7874 -0.4064)
			(stroke
				(width 0.1524)
				(type default)
			)
			(layer "F.SilkS")
		)
		(fp_line
			(start -0.12065 -0.305054)
			(end -0.12065 -0.2794)
			(stroke
				(width 0.1)
				(type default)
			)
			(layer "F.Fab")
		)
		(fp_line
			(start -0.67945 -0.305054)
			(end -0.12065 -0.305054)
			(stroke
				(width 0.1)
				(type default)
			)
			(layer "F.Fab")
		)
		(fp_line
			(start 0.67945 -0.3048)
			(end 0.67945 0.3048)
			(stroke
				(width 0.1)
				(type default)
			)
			(layer "F.Fab")
		)
		(fp_line
			(start 0.12065 -0.3048)
			(end 0.67945 -0.3048)
			(stroke
				(width 0.1)
				(type default)
			)
			(layer "F.Fab")
		)
		(fp_line
			(start 0.12065 -0.2794)
			(end 0.12065 -0.3048)
			(stroke
				(width 0.1)
				(type default)
			)
			(layer "F.Fab")
		)
		(fp_line
			(start -0.12065 -0.2794)
			(end 0.12065 -0.2794)
			(stroke
				(width 0.1)
				(type default)
			)
			(layer "F.Fab")
		)
		(fp_line
			(start 0.120396 0.2794)
			(end -0.12065 0.2794)
			(stroke
				(width 0.1)
				(type default)
			)
			(layer "F.Fab")
		)
		(fp_line
			(start -0.12065 0.2794)
			(end -0.12065 0.3048)
			(stroke
				(width 0.1)
				(type default)
			)
			(layer "F.Fab")
		)
		(fp_line
			(start 0.67945 0.3048)
			(end 0.120396 0.3048)
			(stroke
				(width 0.1)
				(type default)
			)
			(layer "F.Fab")
		)
		(fp_line
			(start 0.120396 0.3048)
			(end 0.120396 0.2794)
			(stroke
				(width 0.1)
				(type default)
			)
			(layer "F.Fab")
		)
		(fp_line
			(start -0.12065 0.3048)
			(end -0.67945 0.3048)
			(stroke
				(width 0.1)
				(type default)
			)
			(layer "F.Fab")
		)
		(fp_line
			(start -0.67945 0.3048)
			(end -0.67945 -0.305054)
			(stroke
				(width 0.1)
				(type default)
			)
			(layer "F.Fab")
		)
		(pad "1" smd circle
			(at -0.40005 0 90)
			(size 0 0)
			(layers "F.Cu" "F.Mask" "F.Paste")
			(net "SMB_BIC_I2C9_MUX1_SSD9_R_SCL")
		)
		(pad "2" smd circle
			(at 0.40005 0 90)
			(size 0 0)
			(layers "F.Cu" "F.Mask" "F.Paste")
			(net "SMB_ISO_SSD9_SCL")
		)
	)
	(footprint ""
		(layer "F.Cu")
		(at 427.42612 -39.73576 -90)
		(property "Reference" "R5584"
			(at 0 0 270)
			(layer "F.SilkS")
			(hide yes)
			(effects
				(font
					(size 1.27 1.27)
				)
			)
		)
		(property "Value" ""
			(at 0 0 270)
			(layer "F.Fab")
			(effects
				(font
					(size 1.27 1.27)
				)
			)
		)
		(duplicate_pad_numbers_are_jumpers no)
		(fp_line
			(start -0.7874 0.4064)
			(end -0.7874 -0.4064)
			(stroke
				(width 0.1524)
				(type default)
			)
			(layer "F.SilkS")
		)
		(fp_line
			(start 0.7874 0.4064)
			(end -0.7874 0.4064)
			(stroke
				(width 0.1524)
				(type default)
			)
			(layer "F.SilkS")
		)
		(fp_line
			(start -0.7874 -0.4064)
			(end 0.7874 -0.4064)
			(stroke
				(width 0.1524)
				(type default)
			)
			(layer "F.SilkS")
		)
		(fp_line
			(start 0.7874 -0.4064)
			(end 0.7874 0.4064)
			(stroke
				(width 0.1524)
				(type default)
			)
			(layer "F.SilkS")
		)
		(fp_line
			(start -0.67945 0.3048)
			(end -0.67945 -0.305054)
			(stroke
				(width 0.1)
				(type default)
			)
			(layer "F.Fab")
		)
		(fp_line
			(start -0.12065 0.3048)
			(end -0.67945 0.3048)
			(stroke
				(width 0.1)
				(type default)
			)
			(layer "F.Fab")
		)
		(fp_line
			(start 0.120396 0.3048)
			(end 0.120396 0.2794)
			(stroke
				(width 0.1)
				(type default)
			)
			(layer "F.Fab")
		)
		(fp_line
			(start 0.67945 0.3048)
			(end 0.120396 0.3048)
			(stroke
				(width 0.1)
				(type default)
			)
			(layer "F.Fab")
		)
		(fp_line
			(start -0.12065 0.2794)
			(end -0.12065 0.3048)
			(stroke
				(width 0.1)
				(type default)
			)
			(layer "F.Fab")
		)
		(fp_line
			(start 0.120396 0.2794)
			(end -0.12065 0.2794)
			(stroke
				(width 0.1)
				(type default)
			)
			(layer "F.Fab")
		)
		(fp_line
			(start -0.12065 -0.2794)
			(end 0.12065 -0.2794)
			(stroke
				(width 0.1)
				(type default)
			)
			(layer "F.Fab")
		)
		(fp_line
			(start 0.12065 -0.2794)
			(end 0.12065 -0.3048)
			(stroke
				(width 0.1)
				(type default)
			)
			(layer "F.Fab")
		)
		(fp_line
			(start 0.12065 -0.3048)
			(end 0.67945 -0.3048)
			(stroke
				(width 0.1)
				(type default)
			)
			(layer "F.Fab")
		)
		(fp_line
			(start 0.67945 -0.3048)
			(end 0.67945 0.3048)
			(stroke
				(width 0.1)
				(type default)
			)
			(layer "F.Fab")
		)
		(fp_line
			(start -0.67945 -0.305054)
			(end -0.12065 -0.305054)
			(stroke
				(width 0.1)
				(type default)
			)
			(layer "F.Fab")
		)
		(fp_line
			(start -0.12065 -0.305054)
			(end -0.12065 -0.2794)
			(stroke
				(width 0.1)
				(type default)
			)
			(layer "F.Fab")
		)
		(pad "1" smd circle
			(at -0.40005 0 270)
			(size 0 0)
			(layers "F.Cu" "F.Mask" "F.Paste")
			(net "P3V3_AUX")
		)
		(pad "2" smd circle
			(at 0.40005 0 270)
			(size 0 0)
			(layers "F.Cu" "F.Mask" "F.Paste")
			(net "SSD15_AUX_P3V3_EN")
		)
	)
)
